# BASEBOARD_FAB2 (Tioga Pass) — schematic netlist excerpt (pin names and nets, part order shuffled) for the footprints in the layout excerpt that follows; sources: Cadence DE-HDL packaged netlist, KiCad conversion of Wiwynn_Tioga_Pass_MB.brd

R2U4  RES  4.75K 1% CHIP  pkg 0402  page 157 : A = P3V3_STBY ; B = FM_CPLD_BMC_PWRDN_N
R774  RES  0.0 5% CHIP  pkg 0402  page 244 : A = P3E_CPU0_PE1_PCH_RXP<13> ; B = P3E_CPU0_PE1_PCH_CON_RXP<13>
R8D20  RES  49.9 1% CHIP  pkg 0402  page 178 : A = SGPIO_PCH_SATA_LOAD ; B = SGPIO_PCH_SATA_LOAD_R

(kicad_pcb
	(version 20260206)
	(generator "pcbnew")
	(generator_version "10.0")
	(general
		(thickness 1.6)
		(legacy_teardrops no)
	)
	(paper "A4")
	(title_block
		(title "Wiwynn_Tioga_Pass_MB.brd")
		(comment 1 "Tioga Pass / footprints 2998-3000 of 4770")
	)
	(layers
		(0 "F.Cu" signal "TOP")
		(4 "In1.Cu" signal "L2GND")
		(6 "In2.Cu" signal "L3")
		(8 "In3.Cu" signal "L4GND")
		(10 "In4.Cu" signal "L5")
		(12 "In5.Cu" signal "L6GND")
		(14 "In6.Cu" signal "L7VCC")
		(16 "In7.Cu" signal "L8VCC")
		(18 "In8.Cu" signal "L9GND")
		(20 "In9.Cu" signal "L10")
		(22 "In10.Cu" signal "L11GND")
		(24 "In11.Cu" signal "L12")
		(26 "In12.Cu" signal "L13GND")
		(2 "B.Cu" signal "BOTTOM")
		(9 "F.Adhes" user "F.Adhesive")
		(11 "B.Adhes" user "B.Adhesive")
		(13 "F.Paste" user "Package Geometry/Pastemask Top")
		(15 "B.Paste" user "Package Geometry/Pastemask Bottom")
		(5 "F.SilkS" user "Ref Des/Silkscreen Top")
		(7 "B.SilkS" user "Ref Des/Silkscreen Bottom")
		(1 "F.Mask" user "Board Geometry/Soldermask Top")
		(3 "B.Mask" user "Board Geometry/Soldermask Bottom")
		(17 "Dwgs.User" user "User.Drawings")
		(19 "Cmts.User" user "User.Comments")
		(21 "Eco1.User" user "User.Eco1")
		(23 "Eco2.User" user "User.Eco2")
		(25 "Edge.Cuts" user "Board Geometry/Outline")
		(27 "Margin" user)
		(31 "F.CrtYd" user "Package Geometry/Place Bound Top")
		(29 "B.CrtYd" user "Package Geometry/Place Bound Bottom")
		(35 "F.Fab" user "Ref Des/Assembly Top")
		(33 "B.Fab" user "Ref Des/Assembly Bottom")
	)
	(footprint ""
		(layer "B.Cu")
		(at 392.43 -87.4395)
		(property "Reference" "R8D20"
			(at 0.8382 -0.67818 0)
			(unlocked yes)
			(layer "B.SilkS")
			(effects
				(font
					(size 0.4064 0.254)
					(thickness 0.1524)
				)
				(justify left mirror)
			)
		)
		(property "Value" ""
			(at 0 0 0)
			(layer "B.Fab")
			(effects
				(font
					(size 1.27 1.27)
				)
				(justify mirror)
			)
		)
		(duplicate_pad_numbers_are_jumpers no)
		(fp_poly
			(pts
				(xy 0.2794 -0.1016) (xy -0.2794 -0.1016) (xy -0.2794 0.9906) (xy 0.2794 0.9906)
			)
			(stroke
				(width 0)
				(type default)
			)
			(fill no)
			(layer "B.CrtYd")
		)
		(fp_line
			(start -0.2794 -0.1016)
			(end 0.2794 -0.1016)
			(stroke
				(width 0.1)
				(type default)
			)
			(layer "B.Fab")
		)
		(fp_line
			(start -0.2794 0.9906)
			(end -0.2794 -0.1016)
			(stroke
				(width 0.1)
				(type default)
			)
			(layer "B.Fab")
		)
		(fp_line
			(start 0.2794 -0.1016)
			(end 0.2794 0.9906)
			(stroke
				(width 0.1)
				(type default)
			)
			(layer "B.Fab")
		)
		(fp_line
			(start 0.2794 0.9906)
			(end -0.2794 0.9906)
			(stroke
				(width 0.1)
				(type default)
			)
			(layer "B.Fab")
		)
		(pad "1" smd rect
			(at 0 0 180)
			(size 0.508 0.508)
			(layers "B.Cu" "B.Mask" "B.Paste")
			(net "SGPIO_PCH_SATA_LOAD")
		)
		(pad "2" smd rect
			(at 0 0.889 180)
			(size 0.508 0.508)
			(layers "B.Cu" "B.Mask" "B.Paste")
			(net "SGPIO_PCH_SATA_LOAD_R")
		)
		(zone
			(layer "B.Cu")
			(hatch none 0.5)
			(connect_pads
				(clearance 0)
			)
			(min_thickness 0.25)
			(keepout
				(tracks allowed)
				(vias not_allowed)
				(pads allowed)
				(copperpour not_allowed)
				(footprints allowed)
			)
			(placement
				(enabled no)
				(sheetname "")
			)
			(fill
				(thermal_gap 0.5)
				(thermal_bridge_width 0.5)
				(island_removal_mode 0)
			)
			(polygon
				(pts
					(xy 392.684 -87.1855) (xy 392.176 -87.1855) (xy 392.176 -86.8045) (xy 392.684 -86.8045)
				)
			)
		)
		(zone
			(layer "B.Cu")
			(hatch none 0.5)
			(connect_pads
				(clearance 0)
			)
			(min_thickness 0.25)
			(keepout
				(tracks not_allowed)
				(vias allowed)
				(pads allowed)
				(copperpour not_allowed)
				(footprints allowed)
			)
			(placement
				(enabled no)
				(sheetname "")
			)
			(fill
				(thermal_gap 0.5)
				(thermal_bridge_width 0.5)
				(island_removal_mode 0)
			)
			(polygon
				(pts
					(xy 392.684 -86.8045) (xy 392.176 -86.8045) (xy 392.176 -87.1855) (xy 392.684 -87.1855)
				)
			)
		)
	)
	(footprint ""
		(layer "B.Cu")
		(at 348.574614 -123.576842 -90)
		(property "Reference" "R774"
			(at 0.8382 -0.67818 270)
			(unlocked yes)
			(layer "B.SilkS")
			(effects
				(font
					(size 0.4064 0.254)
					(thickness 0.1524)
				)
				(justify left mirror)
			)
		)
		(property "Value" ""
			(at 0 0 90)
			(layer "B.Fab")
			(effects
				(font
					(size 1.27 1.27)
				)
				(justify mirror)
			)
		)
		(duplicate_pad_numbers_are_jumpers no)
		(fp_poly
			(pts
				(xy 0.2794 -0.1016) (xy -0.2794 -0.1016) (xy -0.2794 0.9906) (xy 0.2794 0.9906)
			)
			(stroke
				(width 0)
				(type default)
			)
			(fill no)
			(layer "B.CrtYd")
		)
		(fp_line
			(start -0.2794 0.9906)
			(end -0.2794 -0.1016)
			(stroke
				(width 0.1)
				(type default)
			)
			(layer "B.Fab")
		)
		(fp_line
			(start 0.2794 0.9906)
			(end -0.2794 0.9906)
			(stroke
				(width 0.1)
				(type default)
			)
			(layer "B.Fab")
		)
		(fp_line
			(start -0.2794 -0.1016)
			(end 0.2794 -0.1016)
			(stroke
				(width 0.1)
				(type default)
			)
			(layer "B.Fab")
		)
		(fp_line
			(start 0.2794 -0.1016)
			(end 0.2794 0.9906)
			(stroke
				(width 0.1)
				(type default)
			)
			(layer "B.Fab")
		)
		(pad "1" smd rect
			(at 0 0 90)
			(size 0.508 0.508)
			(layers "B.Cu" "B.Mask" "B.Paste")
			(net "P3E_CPU0_PE1_PCH_RXP<13>")
		)
		(pad "2" smd rect
			(at 0 0.889 90)
			(size 0.508 0.508)
			(layers "B.Cu" "B.Mask" "B.Paste")
			(net "P3E_CPU0_PE1_PCH_CON_RXP<13>")
		)
		(zone
			(layer "B.Cu")
			(hatch none 0.5)
			(connect_pads
				(clearance 0)
			)
			(min_thickness 0.25)
			(keepout
				(tracks not_allowed)
				(vias allowed)
				(pads allowed)
				(copperpour not_allowed)
				(footprints allowed)
			)
			(placement
				(enabled no)
				(sheetname "")
			)
			(fill
				(thermal_gap 0.5)
				(thermal_bridge_width 0.5)
				(island_removal_mode 0)
			)
			(polygon
				(pts
					(xy 347.939614 -123.322842) (xy 347.939614 -123.830842) (xy 348.320614 -123.830842) (xy 348.320614 -123.322842)
				)
			)
		)
		(zone
			(layer "B.Cu")
			(hatch none 0.5)
			(connect_pads
				(clearance 0)
			)
			(min_thickness 0.25)
			(keepout
				(tracks allowed)
				(vias not_allowed)
				(pads allowed)
				(copperpour not_allowed)
				(footprints allowed)
			)
			(placement
				(enabled no)
				(sheetname "")
			)
			(fill
				(thermal_gap 0.5)
				(thermal_bridge_width 0.5)
				(island_removal_mode 0)
			)
			(polygon
				(pts
					(xy 348.320614 -123.322842) (xy 348.320614 -123.830842) (xy 347.939614 -123.830842) (xy 347.939614 -123.322842)
				)
			)
		)
	)
	(footprint ""
		(layer "B.Cu")
		(at 401.472146 -40.598852 90)
		(property "Reference" "R2U4"
			(at 0 0 90)
			(layer "B.SilkS")
			(hide yes)
			(effects
				(font
					(size 1.27 1.27)
				)
				(justify mirror)
			)
		)
		(property "Value" ""
			(at 0 0 90)
			(layer "B.Fab")
			(effects
				(font
					(size 1.27 1.27)
				)
				(justify mirror)
			)
		)
		(duplicate_pad_numbers_are_jumpers no)
		(fp_poly
			(pts
				(xy 0.2794 -0.1016) (xy -0.2794 -0.1016) (xy -0.2794 0.9906) (xy 0.2794 0.9906)
			)
			(stroke
				(width 0)
				(type default)
			)
			(fill no)
			(layer "B.CrtYd")
		)
		(fp_line
			(start 0.2794 -0.1016)
			(end 0.2794 0.9906)
			(stroke
				(width 0.1)
				(type default)
			)
			(layer "B.Fab")
		)
		(fp_line
			(start -0.2794 -0.1016)
			(end 0.2794 -0.1016)
			(stroke
				(width 0.1)
				(type default)
			)
			(layer "B.Fab")
		)
		(fp_line
			(start 0.2794 0.9906)
			(end -0.2794 0.9906)
			(stroke
				(width 0.1)
				(type default)
			)
			(layer "B.Fab")
		)
		(fp_line
			(start -0.2794 0.9906)
			(end -0.2794 -0.1016)
			(stroke
				(width 0.1)
				(type default)
			)
			(layer "B.Fab")
		)
		(pad "1" smd rect
			(at 0 0 270)
			(size 0.508 0.508)
			(layers "B.Cu" "B.Mask" "B.Paste")
			(net "P3V3_STBY")
		)
		(pad "2" smd rect
			(at 0 0.889 270)
			(size 0.508 0.508)
			(layers "B.Cu" "B.Mask" "B.Paste")
			(net "FM_CPLD_BMC_PWRDN_N")
		)
		(zone
			(layer "B.Cu")
			(hatch none 0.5)
			(connect_pads
				(clearance 0)
			)
			(min_thickness 0.25)
			(keepout
				(tracks allowed)
				(vias not_allowed)
				(pads allowed)
				(copperpour not_allowed)
				(footprints allowed)
			)
			(placement
				(enabled no)
				(sheetname "")
			)
			(fill
				(thermal_gap 0.5)
				(thermal_bridge_width 0.5)
				(island_removal_mode 0)
			)
			(polygon
				(pts
					(xy 401.726146 -40.852852) (xy 401.726146 -40.344852) (xy 402.107146 -40.344852) (xy 402.107146 -40.852852)
				)
			)
		)
		(zone
			(layer "B.Cu")
			(hatch none 0.5)
			(connect_pads
				(clearance 0)
			)
			(min_thickness 0.25)
			(keepout
				(tracks not_allowed)
				(vias allowed)
				(pads allowed)
				(copperpour not_allowed)
				(footprints allowed)
			)
			(placement
				(enabled no)
				(sheetname "")
			)
			(fill
				(thermal_gap 0.5)
				(thermal_bridge_width 0.5)
				(island_removal_mode 0)
			)
			(polygon
				(pts
					(xy 402.107146 -40.852852) (xy 402.107146 -40.344852) (xy 401.726146 -40.344852) (xy 401.726146 -40.852852)
				)
			)
		)
	)
)
